(kicad_pcb
	(version 20260206)
	(generator "pcbnew")
	(generator_version "10.0")
	(general
		(thickness 1.6)
		(legacy_teardrops no)
	)
	(paper "A4")
	(title_block
		(title "peb — Lightning_PEB_BRD.brd")
		(comment 1 "Lightning (Wiwynn / Facebook NVMe JBOF) / footprints 879-885 of 2563")
	)
	(layers
		(0 "F.Cu" signal "TOP")
		(4 "In1.Cu" signal "L2GND")
		(6 "In2.Cu" signal "L3")
		(8 "In3.Cu" signal "L4VCC")
		(10 "In4.Cu" signal "L5VCC")
		(12 "In5.Cu" signal "L6")
		(14 "In6.Cu" signal "L7GND")
		(2 "B.Cu" signal "BOTTOM")
		(9 "F.Adhes" user "F.Adhesive")
		(11 "B.Adhes" user "B.Adhesive")
		(13 "F.Paste" user "Package Geometry/Pastemask Top")
		(15 "B.Paste" user "Package Geometry/Pastemask Bottom")
		(5 "F.SilkS" user "Ref Des/Silkscreen Top")
		(7 "B.SilkS" user "Ref Des/Silkscreen Bottom")
		(1 "F.Mask" user "Board Geometry/Soldermask Top")
		(3 "B.Mask" user "Board Geometry/Soldermask Bottom")
		(17 "Dwgs.User" user "User.Drawings")
		(19 "Cmts.User" user "User.Comments")
		(21 "Eco1.User" user "User.Eco1")
		(23 "Eco2.User" user "User.Eco2")
		(25 "Edge.Cuts" user "Board Geometry/Outline")
		(27 "Margin" user)
		(31 "F.CrtYd" user "Package Geometry/Place Bound Top")
		(29 "B.CrtYd" user "Package Geometry/Place Bound Bottom")
		(35 "F.Fab" user "Ref Des/Assembly Top")
		(33 "B.Fab" user "Ref Des/Assembly Bottom")
	)
	(footprint ""
		(layer "F.Cu")
		(at 23.2664 -86.9696)
		(property "Reference" "R402"
			(at 0 0 0)
			(layer "F.SilkS")
			(hide yes)
			(effects
				(font
					(size 1.27 1.27)
				)
			)
		)
		(property "Value" "3K3R2F-2-GP"
			(at 0.064008 -3.993896 0)
			(unlocked yes)
			(layer "F.Fab")
			(hide yes)
			(effects
				(font
					(size 1.016 1.016)
					(thickness 0.1524)
				)
			)
		)
		(property "Device Type" "R402H16"
			(at 0.064008 -5.517896 0)
			(unlocked yes)
			(layer "F.Fab")
			(hide yes)
			(effects
				(font
					(size 1.016 1.016)
					(thickness 0.1524)
				)
			)
		)
		(duplicate_pad_numbers_are_jumpers no)
		(fp_line
			(start -0.508 -0.9398)
			(end -0.508 0.9398)
			(stroke
				(width 0.1524)
				(type default)
			)
			(layer "F.SilkS")
		)
		(fp_line
			(start 0.508 -0.9398)
			(end -0.508 -0.9398)
			(stroke
				(width 0.1524)
				(type default)
			)
			(layer "F.SilkS")
		)
		(fp_rect
			(start -0.508 0.9398)
			(end 0.508 -0.9398)
			(stroke
				(width 0)
				(type default)
			)
			(fill no)
			(layer "F.CrtYd")
		)
		(fp_rect
			(start -0.508 0.9398)
			(end 0.508 -0.9398)
			(stroke
				(width 0)
				(type default)
			)
			(fill no)
			(layer "F.Fab")
		)
		(pad "1" smd custom
			(at 0 -0.4445)
			(size 0.1397 0.1397)
			(layers "F.Cu" "F.Mask" "F.Paste")
			(net "P3V3_STBY")
			(options
				(clearance outline)
				(anchor circle)
			)
			(primitives
				(gr_poly
					(pts
						(arc
							(start -0.1778 -0.2794)
							(mid -0.249642 -0.249642)
							(end -0.2794 -0.1778)
						)
						(arc
							(start -0.2794 0.1778)
							(mid -0.249642 0.249642)
							(end -0.1778 0.2794)
						)
						(arc
							(start 0.1778 0.2794)
							(mid 0.249642 0.249642)
							(end 0.2794 0.1778)
						)
						(arc
							(start 0.2794 -0.1778)
							(mid 0.249642 -0.249642)
							(end 0.1778 -0.2794)
						)
					)
					(width 0)
					(fill yes)
				)
			)
		)
		(pad "2" smd custom
			(at 0 0.4445)
			(size 0.1397 0.1397)
			(layers "F.Cu" "F.Mask" "F.Paste")
			(net "NIC_JTCK")
			(options
				(clearance outline)
				(anchor circle)
			)
			(primitives
				(gr_poly
					(pts
						(arc
							(start -0.1778 -0.2794)
							(mid -0.249642 -0.249642)
							(end -0.2794 -0.1778)
						)
						(arc
							(start -0.2794 0.1778)
							(mid -0.249642 0.249642)
							(end -0.1778 0.2794)
						)
						(arc
							(start 0.1778 0.2794)
							(mid 0.249642 0.249642)
							(end 0.2794 0.1778)
						)
						(arc
							(start 0.2794 -0.1778)
							(mid 0.249642 -0.249642)
							(end 0.1778 -0.2794)
						)
					)
					(width 0)
					(fill yes)
				)
			)
		)
	)
	(footprint ""
		(layer "F.Cu")
		(at 19.304 -154.432)
		(property "Reference" "R8005"
			(at 0 0 0)
			(layer "F.SilkS")
			(hide yes)
			(effects
				(font
					(size 1.27 1.27)
				)
			)
		)
		(property "Value" "0R2J-2-GP"
			(at 0.064008 -3.993896 0)
			(unlocked yes)
			(layer "F.Fab")
			(hide yes)
			(effects
				(font
					(size 1.016 1.016)
					(thickness 0.1524)
				)
			)
		)
		(property "Device Type" "R402H16"
			(at 0.064008 -5.517896 0)
			(unlocked yes)
			(layer "F.Fab")
			(hide yes)
			(effects
				(font
					(size 1.016 1.016)
					(thickness 0.1524)
				)
			)
		)
		(duplicate_pad_numbers_are_jumpers no)
		(fp_line
			(start -0.508 -0.9398)
			(end -0.508 0.9398)
			(stroke
				(width 0.1524)
				(type default)
			)
			(layer "F.SilkS")
		)
		(fp_line
			(start 0.508 -0.9398)
			(end -0.508 -0.9398)
			(stroke
				(width 0.1524)
				(type default)
			)
			(layer "F.SilkS")
		)
		(fp_rect
			(start -0.508 0.9398)
			(end 0.508 -0.9398)
			(stroke
				(width 0)
				(type default)
			)
			(fill no)
			(layer "F.CrtYd")
		)
		(fp_rect
			(start -0.508 0.9398)
			(end 0.508 -0.9398)
			(stroke
				(width 0)
				(type default)
			)
			(fill no)
			(layer "F.Fab")
		)
		(pad "1" smd custom
			(at 0 -0.4445)
			(size 0.1397 0.1397)
			(layers "F.Cu" "F.Mask" "F.Paste")
			(net "HOST_I2C_RESET_N_D")
			(options
				(clearance outline)
				(anchor circle)
			)
			(primitives
				(gr_poly
					(pts
						(arc
							(start -0.1778 -0.2794)
							(mid -0.249642 -0.249642)
							(end -0.2794 -0.1778)
						)
						(arc
							(start -0.2794 0.1778)
							(mid -0.249642 0.249642)
							(end -0.1778 0.2794)
						)
						(arc
							(start 0.1778 0.2794)
							(mid 0.249642 0.249642)
							(end 0.2794 0.1778)
						)
						(arc
							(start 0.2794 -0.1778)
							(mid 0.249642 -0.249642)
							(end 0.1778 -0.2794)
						)
					)
					(width 0)
					(fill yes)
				)
			)
		)
		(pad "2" smd custom
			(at 0 0.4445)
			(size 0.1397 0.1397)
			(layers "F.Cu" "F.Mask" "F.Paste")
			(net "FM_BMC_RESET_Q36")
			(options
				(clearance outline)
				(anchor circle)
			)
			(primitives
				(gr_poly
					(pts
						(arc
							(start -0.1778 -0.2794)
							(mid -0.249642 -0.249642)
							(end -0.2794 -0.1778)
						)
						(arc
							(start -0.2794 0.1778)
							(mid -0.249642 0.249642)
							(end -0.1778 0.2794)
						)
						(arc
							(start 0.1778 0.2794)
							(mid 0.249642 0.249642)
							(end 0.2794 0.1778)
						)
						(arc
							(start 0.2794 -0.1778)
							(mid 0.249642 -0.249642)
							(end 0.1778 -0.2794)
						)
					)
					(width 0)
					(fill yes)
				)
			)
		)
	)
	(footprint ""
		(layer "F.Cu")
		(at 159.807402 -53.189632 90)
		(property "Reference" "R76"
			(at 0 0 90)
			(layer "F.SilkS")
			(hide yes)
			(effects
				(font
					(size 1.27 1.27)
				)
			)
		)
		(property "Value" "0R2J-2-GP"
			(at 0.064008 -3.993896 90)
			(unlocked yes)
			(layer "F.Fab")
			(hide yes)
			(effects
				(font
					(size 1.016 1.016)
					(thickness 0.1524)
				)
			)
		)
		(property "Device Type" "R402H16"
			(at 0.064008 -5.517896 90)
			(unlocked yes)
			(layer "F.Fab")
			(hide yes)
			(effects
				(font
					(size 1.016 1.016)
					(thickness 0.1524)
				)
			)
		)
		(duplicate_pad_numbers_are_jumpers no)
		(fp_line
			(start 0.508 -0.9398)
			(end -0.508 -0.9398)
			(stroke
				(width 0.1524)
				(type default)
			)
			(layer "F.SilkS")
		)
		(fp_line
			(start -0.508 -0.9398)
			(end -0.508 0.9398)
			(stroke
				(width 0.1524)
				(type default)
			)
			(layer "F.SilkS")
		)
		(fp_rect
			(start -0.508 0.9398)
			(end 0.508 -0.9398)
			(stroke
				(width 0)
				(type default)
			)
			(fill no)
			(layer "F.CrtYd")
		)
		(fp_rect
			(start -0.508 0.9398)
			(end 0.508 -0.9398)
			(stroke
				(width 0)
				(type default)
			)
			(fill no)
			(layer "F.Fab")
		)
		(pad "1" smd custom
			(at 0 -0.4445 90)
			(size 0.1397 0.1397)
			(layers "F.Cu" "F.Mask" "F.Paste")
			(net "P0V9_VFB_R")
			(options
				(clearance outline)
				(anchor circle)
			)
			(primitives
				(gr_poly
					(pts
						(arc
							(start -0.1778 -0.2794)
							(mid -0.249642 -0.249642)
							(end -0.2794 -0.1778)
						)
						(arc
							(start -0.2794 0.1778)
							(mid -0.249642 0.249642)
							(end -0.1778 0.2794)
						)
						(arc
							(start 0.1778 0.2794)
							(mid 0.249642 0.249642)
							(end 0.2794 0.1778)
						)
						(arc
							(start 0.2794 -0.1778)
							(mid 0.249642 -0.249642)
							(end 0.1778 -0.2794)
						)
					)
					(width 0)
					(fill yes)
				)
			)
		)
		(pad "2" smd custom
			(at 0 0.4445 90)
			(size 0.1397 0.1397)
			(layers "F.Cu" "F.Mask" "F.Paste")
			(net "DUT_AVD_PCIE")
			(options
				(clearance outline)
				(anchor circle)
			)
			(primitives
				(gr_poly
					(pts
						(arc
							(start -0.1778 -0.2794)
							(mid -0.249642 -0.249642)
							(end -0.2794 -0.1778)
						)
						(arc
							(start -0.2794 0.1778)
							(mid -0.249642 0.249642)
							(end -0.1778 0.2794)
						)
						(arc
							(start 0.1778 0.2794)
							(mid 0.249642 0.249642)
							(end 0.2794 0.1778)
						)
						(arc
							(start 0.2794 -0.1778)
							(mid 0.249642 -0.249642)
							(end 0.1778 -0.2794)
						)
					)
					(width 0)
					(fill yes)
				)
			)
		)
	)
	(footprint ""
		(layer "F.Cu")
		(at 331.597 -99.568 180)
		(property "Reference" "R4158"
			(at 0 0 180)
			(layer "F.SilkS")
			(hide yes)
			(effects
				(font
					(size 1.27 1.27)
				)
			)
		)
		(property "Value" "4K7R2F-GP"
			(at 0.064008 -3.993896 180)
			(unlocked yes)
			(layer "F.Fab")
			(hide yes)
			(effects
				(font
					(size 1.016 1.016)
					(thickness 0.1524)
				)
			)
		)
		(property "Device Type" "R402H16"
			(at 0.064008 -5.517896 180)
			(unlocked yes)
			(layer "F.Fab")
			(hide yes)
			(effects
				(font
					(size 1.016 1.016)
					(thickness 0.1524)
				)
			)
		)
		(duplicate_pad_numbers_are_jumpers no)
		(fp_line
			(start 0.508 -0.9398)
			(end -0.508 -0.9398)
			(stroke
				(width 0.1524)
				(type default)
			)
			(layer "F.SilkS")
		)
		(fp_line
			(start -0.508 -0.9398)
			(end -0.508 0.9398)
			(stroke
				(width 0.1524)
				(type default)
			)
			(layer "F.SilkS")
		)
		(fp_rect
			(start -0.508 0.9398)
			(end 0.508 -0.9398)
			(stroke
				(width 0)
				(type default)
			)
			(fill no)
			(layer "F.CrtYd")
		)
		(fp_rect
			(start -0.508 0.9398)
			(end 0.508 -0.9398)
			(stroke
				(width 0)
				(type default)
			)
			(fill no)
			(layer "F.Fab")
		)
		(pad "1" smd custom
			(at 0 -0.4445 180)
			(size 0.1397 0.1397)
			(layers "F.Cu" "F.Mask" "F.Paste")
			(net "VS1_LED")
			(options
				(clearance outline)
				(anchor circle)
			)
			(primitives
				(gr_poly
					(pts
						(arc
							(start -0.1778 -0.2794)
							(mid -0.249642 -0.249642)
							(end -0.2794 -0.1778)
						)
						(arc
							(start -0.2794 0.1778)
							(mid -0.249642 0.249642)
							(end -0.1778 0.2794)
						)
						(arc
							(start 0.1778 0.2794)
							(mid 0.249642 0.249642)
							(end 0.2794 0.1778)
						)
						(arc
							(start 0.2794 -0.1778)
							(mid 0.249642 -0.249642)
							(end 0.1778 -0.2794)
						)
					)
					(width 0)
					(fill yes)
				)
			)
		)
		(pad "2" smd custom
			(at 0 0.4445 180)
			(size 0.1397 0.1397)
			(layers "F.Cu" "F.Mask" "F.Paste")
			(net "P3V3_STBY")
			(options
				(clearance outline)
				(anchor circle)
			)
			(primitives
				(gr_poly
					(pts
						(arc
							(start -0.1778 -0.2794)
							(mid -0.249642 -0.249642)
							(end -0.2794 -0.1778)
						)
						(arc
							(start -0.2794 0.1778)
							(mid -0.249642 0.249642)
							(end -0.1778 0.2794)
						)
						(arc
							(start 0.1778 0.2794)
							(mid 0.249642 0.249642)
							(end 0.2794 0.1778)
						)
						(arc
							(start 0.2794 -0.1778)
							(mid 0.249642 -0.249642)
							(end 0.1778 -0.2794)
						)
					)
					(width 0)
					(fill yes)
				)
			)
		)
	)
	(footprint ""
		(layer "F.Cu")
		(at 154.45486 -84.41944)
		(property "Reference" "R98"
			(at 0 0 0)
			(layer "F.SilkS")
			(hide yes)
			(effects
				(font
					(size 1.27 1.27)
				)
			)
		)
		(property "Value" "10KR2F-2-GP"
			(at 0.064008 -3.993896 0)
			(unlocked yes)
			(layer "F.Fab")
			(hide yes)
			(effects
				(font
					(size 1.016 1.016)
					(thickness 0.1524)
				)
			)
		)
		(property "Device Type" "R402H16"
			(at 0.064008 -5.517896 0)
			(unlocked yes)
			(layer "F.Fab")
			(hide yes)
			(effects
				(font
					(size 1.016 1.016)
					(thickness 0.1524)
				)
			)
		)
		(duplicate_pad_numbers_are_jumpers no)
		(fp_line
			(start -0.508 -0.9398)
			(end -0.508 0.9398)
			(stroke
				(width 0.1524)
				(type default)
			)
			(layer "F.SilkS")
		)
		(fp_line
			(start 0.508 -0.9398)
			(end -0.508 -0.9398)
			(stroke
				(width 0.1524)
				(type default)
			)
			(layer "F.SilkS")
		)
		(fp_rect
			(start -0.508 0.9398)
			(end 0.508 -0.9398)
			(stroke
				(width 0)
				(type default)
			)
			(fill no)
			(layer "F.CrtYd")
		)
		(fp_rect
			(start -0.508 0.9398)
			(end 0.508 -0.9398)
			(stroke
				(width 0)
				(type default)
			)
			(fill no)
			(layer "F.Fab")
		)
		(pad "1" smd custom
			(at 0 -0.4445)
			(size 0.1397 0.1397)
			(layers "F.Cu" "F.Mask" "F.Paste")
			(net "CLKGNE_SADR_R")
			(options
				(clearance outline)
				(anchor circle)
			)
			(primitives
				(gr_poly
					(pts
						(arc
							(start -0.1778 -0.2794)
							(mid -0.249642 -0.249642)
							(end -0.2794 -0.1778)
						)
						(arc
							(start -0.2794 0.1778)
							(mid -0.249642 0.249642)
							(end -0.1778 0.2794)
						)
						(arc
							(start 0.1778 0.2794)
							(mid 0.249642 0.249642)
							(end 0.2794 0.1778)
						)
						(arc
							(start 0.2794 -0.1778)
							(mid 0.249642 -0.249642)
							(end 0.1778 -0.2794)
						)
					)
					(width 0)
					(fill yes)
				)
			)
		)
		(pad "2" smd custom
			(at 0 0.4445)
			(size 0.1397 0.1397)
			(layers "F.Cu" "F.Mask" "F.Paste")
			(net "P1V8_STBY")
			(options
				(clearance outline)
				(anchor circle)
			)
			(primitives
				(gr_poly
					(pts
						(arc
							(start -0.1778 -0.2794)
							(mid -0.249642 -0.249642)
							(end -0.2794 -0.1778)
						)
						(arc
							(start -0.2794 0.1778)
							(mid -0.249642 0.249642)
							(end -0.1778 0.2794)
						)
						(arc
							(start 0.1778 0.2794)
							(mid 0.249642 0.249642)
							(end 0.2794 0.1778)
						)
						(arc
							(start 0.2794 -0.1778)
							(mid 0.249642 -0.249642)
							(end 0.1778 -0.2794)
						)
					)
					(width 0)
					(fill yes)
				)
			)
		)
	)
	(footprint ""
		(layer "F.Cu")
		(at 87.8078 -85.2424 90)
		(property "Reference" "SR948"
			(at 0 0 90)
			(layer "F.SilkS")
			(hide yes)
			(effects
				(font
					(size 1.27 1.27)
				)
			)
		)
		(property "Value" "0R2J-2-GP"
			(at 0.064008 -3.993896 90)
			(unlocked yes)
			(layer "F.Fab")
			(hide yes)
			(effects
				(font
					(size 1.016 1.016)
					(thickness 0.1524)
				)
			)
		)
		(property "Device Type" "R402H16"
			(at 0.064008 -5.517896 90)
			(unlocked yes)
			(layer "F.Fab")
			(hide yes)
			(effects
				(font
					(size 1.016 1.016)
					(thickness 0.1524)
				)
			)
		)
		(duplicate_pad_numbers_are_jumpers no)
		(fp_line
			(start 0.508 -0.9398)
			(end -0.508 -0.9398)
			(stroke
				(width 0.1524)
				(type default)
			)
			(layer "F.SilkS")
		)
		(fp_line
			(start -0.508 -0.9398)
			(end -0.508 0.9398)
			(stroke
				(width 0.1524)
				(type default)
			)
			(layer "F.SilkS")
		)
		(fp_rect
			(start -0.508 0.9398)
			(end 0.508 -0.9398)
			(stroke
				(width 0)
				(type default)
			)
			(fill no)
			(layer "F.CrtYd")
		)
		(fp_rect
			(start -0.508 0.9398)
			(end 0.508 -0.9398)
			(stroke
				(width 0)
				(type default)
			)
			(fill no)
			(layer "F.Fab")
		)
		(pad "1" smd custom
			(at 0 -0.4445 90)
			(size 0.1397 0.1397)
			(layers "F.Cu" "F.Mask" "F.Paste")
			(net "EXP_SMART_TX")
			(options
				(clearance outline)
				(anchor circle)
			)
			(primitives
				(gr_poly
					(pts
						(arc
							(start -0.1778 -0.2794)
							(mid -0.249642 -0.249642)
							(end -0.2794 -0.1778)
						)
						(arc
							(start -0.2794 0.1778)
							(mid -0.249642 0.249642)
							(end -0.1778 0.2794)
						)
						(arc
							(start 0.1778 0.2794)
							(mid 0.249642 0.249642)
							(end 0.2794 0.1778)
						)
						(arc
							(start 0.2794 -0.1778)
							(mid 0.249642 -0.249642)
							(end 0.1778 -0.2794)
						)
					)
					(width 0)
					(fill yes)
				)
			)
		)
		(pad "2" smd custom
			(at 0 0.4445 90)
			(size 0.1397 0.1397)
			(layers "F.Cu" "F.Mask" "F.Paste")
			(net "EXP_SMART_TX_R")
			(options
				(clearance outline)
				(anchor circle)
			)
			(primitives
				(gr_poly
					(pts
						(arc
							(start -0.1778 -0.2794)
							(mid -0.249642 -0.249642)
							(end -0.2794 -0.1778)
						)
						(arc
							(start -0.2794 0.1778)
							(mid -0.249642 0.249642)
							(end -0.1778 0.2794)
						)
						(arc
							(start 0.1778 0.2794)
							(mid 0.249642 0.249642)
							(end 0.2794 0.1778)
						)
						(arc
							(start 0.2794 -0.1778)
							(mid 0.249642 -0.249642)
							(end 0.1778 -0.2794)
						)
					)
					(width 0)
					(fill yes)
				)
			)
		)
	)
	(footprint ""
		(layer "F.Cu")
		(at 17.7038 -177.9778)
		(property "Reference" "C339"
			(at 0 0 0)
			(layer "F.SilkS")
			(hide yes)
			(effects
				(font
					(size 1.27 1.27)
				)
			)
		)
		(property "Value" "SC22UF16V6KX-GP"
			(at 0 -6.8072 0)
			(unlocked yes)
			(layer "F.Fab")
			(hide yes)
			(effects
				(font
					(size 1.016 1.016)
					(thickness 0.1524)
				)
			)
		)
		(property "Device Type" "C1206H75"
			(at 0 -8.7122 0)
			(unlocked yes)
			(layer "F.Fab")
			(hide yes)
			(effects
				(font
					(size 1.016 1.016)
					(thickness 0.1524)
				)
			)
		)
		(duplicate_pad_numbers_are_jumpers no)
		(fp_line
			(start -1.016 -2.2352)
			(end -1.016 -0.8382)
			(stroke
				(width 0.1524)
				(type default)
			)
			(layer "F.SilkS")
		)
		(fp_line
			(start -1.016 2.2352)
			(end -1.016 0.8128)
			(stroke
				(width 0.1524)
				(type default)
			)
			(layer "F.SilkS")
		)
		(fp_line
			(start 1.016 -2.2352)
			(end -1.016 -2.2352)
			(stroke
				(width 0.1524)
				(type default)
			)
			(layer "F.SilkS")
		)
		(fp_line
			(start 1.016 -2.2352)
			(end 1.016 -0.8382)
			(stroke
				(width 0.1524)
				(type default)
			)
			(layer "F.SilkS")
		)
		(fp_line
			(start 1.016 0.8382)
			(end 1.016 2.2352)
			(stroke
				(width 0.1524)
				(type default)
			)
			(layer "F.SilkS")
		)
		(fp_line
			(start 1.016 2.2352)
			(end -1.016 2.2352)
			(stroke
				(width 0.1524)
				(type default)
			)
			(layer "F.SilkS")
		)
		(fp_rect
			(start -1.0922 2.3114)
			(end 1.0922 -2.3114)
			(stroke
				(width 0)
				(type default)
			)
			(fill no)
			(layer "F.CrtYd")
		)
		(fp_poly
			(pts
				(xy -1.0922 -2.3114) (xy 1.0922 -2.3114) (xy 1.0922 2.3114) (xy -1.0922 2.3114)
			)
			(stroke
				(width 0)
				(type default)
			)
			(fill no)
			(layer "F.Fab")
		)
		(pad "1" smd rect
			(at 0 -1.397)
			(size 1.651 1.27)
			(layers "F.Cu" "F.Mask" "F.Paste")
			(net "MB0_HS_ENABLE")
		)
		(pad "2" smd rect
			(at 0 1.397)
			(size 1.651 1.27)
			(layers "F.Cu" "F.Mask" "F.Paste")
			(net "GND")
		)
	)
)
